#ISCELL
  mstr_misc dns *
  *
#ISCELL
  mstr_symbols intel_corp_bpage *
  *
#CELL
  mstr_ttl ttl1g126_a *
  page200_i103
#ISCELL
  mstr_symbols agnd0 *
  page200_i106
#CELL
  mstr_discrete res *
  page200_i107
#CELL
  mstr_discrete res *
  page200_i108
#ISCELL
  mstr_symbols p12v_stby *
  page200_i109
#ISCELL
  mstr_symbols gnd *
  page200_i114
#ISCELL
  mstr_standard offpage *
  page200_i118
#ISCELL
  mstr_standard offpage *
  page200_i121
#ISCELL
  mstr_standard offpage *
  page200_i134
#ISCELL
  mstr_standard offpage *
  page200_i135
#ISCELL
  mstr_symbols p12v_stby *
  page200_i144
#CELL
  mstr_discrete res *
  page200_i145
#CELL
  mstr_discrete res *
  page200_i146
#ISCELL
  mstr_symbols agnd0 *
  page200_i147
#CELL
  mstr_discrete res *
  page200_i149
#ISCELL
  mstr_symbols p3v3_stby *
  page200_i150
#ISCELL
  mstr_standard offpage *
  page200_i153
#CELL
  mstr_discrete res *
  page200_i154
#CELL
  mstr_discrete cap *
  page200_i155
#ISCELL
  mstr_symbols gnd *
  page200_i156
#ISCELL
  mstr_symbols p3v3_stby *
  page200_i157
#CELL
  mstr_discrete res *
  page200_i158
#CELL
  mstr_vreg tps3700 *
  page200_i163
#CELL
  mstr_vreg tps3700 *
  page200_i170
#CELL
  mstr_discrete res *
  page200_i172
#CELL
  mstr_discrete res *
  page200_i173
#CELL
  mstr_discrete res *
  page200_i174
#CELL
  mstr_discrete res *
  page200_i175
#ISCELL
  mstr_symbols gnd *
  page200_i178
#ISCELL
  mstr_symbols gnd *
  page200_i179
#ISCELL
  mstr_symbols agnd0 *
  page200_i180
#ISCELL
  mstr_symbols agnd0 *
  page200_i181
#ISCELL
  mstr_symbols gnd *
  page200_i183
#ISCELL
  mstr_symbols p12v_stby *
  page200_i184
#CELL
  dev_discrete cap_a *
  page200_i185
#ISCELL
  mstr_symbols agnd0 *
  page200_i186
#CELL
  dev_discrete cap_a *
  page200_i187
#ISCELL
  mstr_symbols agnd0 *
  page200_i188
#CELL
  mstr_discrete res *
  page200_i189
#ISCELL
  mstr_symbols p3v3_stby *
  page200_i190
#CELL
  mstr_discrete res *
  page200_i191
#CELL
  mstr_discrete res *
  page200_i192
#ISCELL
  mstr_symbols p3v3_stby *
  page200_i194
#CELL
  mstr_discrete fet_n_dual *
  page200_i196
#ISCELL
  mstr_symbols gnd *
  page200_i197
#CELL
  mstr_discrete res *
  page200_i198
#CELL
  mstr_discrete fet_n_dual *
  page200_i199
#CELL
  mstr_vreg tps3700 *
  page200_i200
#CELL
  dev_discrete cap_a *
  page200_i201
#ISCELL
  mstr_symbols gnd *
  page200_i202
#CELL
  mstr_discrete fet_n *
  page200_i203
#CELL
  mstr_discrete res *
  page200_i204
#ISCELL
  mstr_symbols p3v3_stby *
  page200_i205
#ISCELL
  mstr_symbols gnd *
  page200_i206
#ISCELL
  mstr_standard offpage *
  page200_i207
#CELL
  mstr_discrete res *
  page200_i210
#ISCELL
  mstr_symbols p3v3_stby *
  page200_i211
#CELL
  mstr_discrete diode *
  page200_i213
#CELL
  mstr_discrete diode *
  page200_i214
#CELL
  mstr_discrete res *
  page200_i215
#ISCELL
  mstr_symbols p3v3_stby *
  page200_i216
#ISCELL
  mstr_symbols agnd0 *
  page200_i217
#CELL
  mstr_discrete res *
  page200_i218
#ISCELL
  mstr_symbols agnd0 *
  page200_i219
#CELL
  mstr_discrete diode *
  page200_i220
#ISCELL
  mstr_symbols gnd *
  page200_i221
#CELL
  mstr_discrete res *
  page200_i222
#ISCELL
  mstr_symbols p12v_stby *
  page200_i223
#ISCELL
  mstr_standard offpage *
  page200_i224
#CELL
  mstr_discrete fet_n *
  page200_i225
#ISCELL
  mstr_standard offpage *
  page200_i226
#ISCELL
  mstr_symbols gnd *
  page200_i227
#CELL
  mstr_discrete res *
  page200_i229
#CELL
  mstr_discrete res *
  page200_i230
#ISCELL
  mstr_symbols gnd *
  page200_i231
#ISCELL
  mstr_symbols p3v3_stby *
  page200_i232
#CELL
  w_hdl sc22p50v2jn-4gp *
  page200_i235
#CELL
  w_hdl sc22p50v2jn-4gp *
  page200_i236
#ISCELL
  mstr_symbols agnd0 *
  page200_i237
#ISCELL
  mstr_symbols agnd0 *
  page200_i238
#CELL
  w_hdl 232kr2f-2-gp *
  page200_i239
#CELL
  dev_discrete cap_a *
  page200_i36
#ISCELL
  mstr_standard offpage *
  page200_i37
#ISCELL
  mstr_standard offpage *
  page200_i38
#ISCELL
  mstr_symbols agnd0 *
  page200_i39
#CELL
  dev_discrete cap_a *
  page200_i40
#ISCELL
  mstr_symbols agnd0 *
  page200_i41
#CELL
  dev_discrete cap_a *
  page200_i42
#CELL
  mstr_discrete res *
  page200_i43
#CELL
  mstr_discrete res *
  page200_i44
#ISCELL
  mstr_standard offpage *
  page200_i45
#ISCELL
  mstr_standard offpage *
  page200_i46
#CELL
  mstr_discrete res *
  page200_i47
#CELL
  mstr_discrete res *
  page200_i48
#CELL
  mstr_discrete res_pwr *
  page200_i49
#CELL
  mstr_discrete res_pwr *
  page200_i50
#CELL
  mstr_discrete res *
  page200_i51
#CELL
  mstr_discrete res *
  page200_i52
#ISCELL
  mstr_symbols p12v_psu *
  page200_i53
#CELL
  mstr_discrete mosfetn_1d3s *
  page200_i54
#ISCELL
  mstr_standard offpage *
  page200_i55
#CELL
  mstr_discrete res *
  page200_i56
#CELL
  mstr_discrete mosfetn_1d3s *
  page200_i57
#CELL
  mstr_discrete res *
  page200_i58
#CELL
  mstr_discrete mosfetn_1d3s *
  page200_i59
#CELL
  mstr_discrete res *
  page200_i60
#ISCELL
  mstr_symbols p12v_stby *
  page200_i64
#CELL
  mstr_discrete res *
  page200_i70
#CELL
  mstr_discrete res *
  page200_i71
#ISCELL
  mstr_standard offpage *
  page200_i72
#ISCELL
  mstr_symbols p3v3_stby *
  page200_i78
#CELL
  mstr_discrete res *
  page200_i86
#ISCELL
  mstr_standard offpage *
  page200_i92
#ISCELL
  mstr_standard offpage *
  page200_i94
